(kicad_pcb
	(version 20260206)
	(generator "pcbnew")
	(generator_version "10.0")
	(general
		(thickness 1.6)
		(legacy_teardrops no)
	)
	(paper "A4")
	(title_block
		(title "Bryce Canyon_F.DPB_16315-1-OCP.brd")
		(comment 1 "Bryce Canyon / footprints 1087-1093 of 2223")
	)
	(layers
		(0 "F.Cu" signal "TOP")
		(4 "In1.Cu" signal "L2GND")
		(6 "In2.Cu" signal "L3")
		(8 "In3.Cu" signal "L4GND")
		(10 "In4.Cu" signal "L5")
		(12 "In5.Cu" signal "L6VCC")
		(14 "In6.Cu" signal "L7VCC")
		(16 "In7.Cu" signal "L8")
		(18 "In8.Cu" signal "L9GND")
		(20 "In9.Cu" signal "L10")
		(22 "In10.Cu" signal "L11GND")
		(2 "B.Cu" signal "BOTTOM")
		(9 "F.Adhes" user "F.Adhesive")
		(11 "B.Adhes" user "B.Adhesive")
		(13 "F.Paste" user "Package Geometry/Pastemask Top")
		(15 "B.Paste" user "Package Geometry/Pastemask Bottom")
		(5 "F.SilkS" user "Ref Des/Silkscreen Top")
		(7 "B.SilkS" user "Ref Des/Silkscreen Bottom")
		(1 "F.Mask" user "Board Geometry/Soldermask Top")
		(3 "B.Mask" user "Board Geometry/Soldermask Bottom")
		(17 "Dwgs.User" user "User.Drawings")
		(19 "Cmts.User" user "User.Comments")
		(21 "Eco1.User" user "User.Eco1")
		(23 "Eco2.User" user "User.Eco2")
		(25 "Edge.Cuts" user "Board Geometry/Outline")
		(27 "Margin" user)
		(31 "F.CrtYd" user "Package Geometry/Place Bound Top")
		(29 "B.CrtYd" user "Package Geometry/Place Bound Bottom")
		(35 "F.Fab" user "Ref Des/Assembly Top")
		(33 "B.Fab" user "Ref Des/Assembly Bottom")
	)
	(footprint ""
		(layer "F.Cu")
		(at 431.454052 -62.016894)
		(property "Reference" "Q200"
			(at 0 0 0)
			(layer "F.SilkS")
			(hide yes)
			(effects
				(font
					(size 1.27 1.27)
				)
			)
		)
		(property "Value" "AO4407AL-GP"
			(at -3.707384 -1.5367 0)
			(unlocked yes)
			(layer "F.Fab")
			(hide yes)
			(effects
				(font
					(size 1.016 1.016)
					(thickness 0.1524)
				)
			)
		)
		(property "Device Type" "SOIC8H69"
			(at -3.707384 -3.0607 0)
			(unlocked yes)
			(layer "F.Fab")
			(hide yes)
			(effects
				(font
					(size 1.016 1.016)
					(thickness 0.1524)
				)
			)
		)
		(duplicate_pad_numbers_are_jumpers no)
		(fp_line
			(start -2.7432 -1.4224)
			(end -2.7432 1.4224)
			(stroke
				(width 0.1524)
				(type default)
			)
			(layer "F.SilkS")
		)
		(fp_line
			(start -2.7432 1.4224)
			(end -2.6416 1.4224)
			(stroke
				(width 0.1524)
				(type default)
			)
			(layer "F.SilkS")
		)
		(fp_line
			(start -2.7432 1.4224)
			(end 2.1336 1.4224)
			(stroke
				(width 0.1524)
				(type default)
			)
			(layer "F.SilkS")
		)
		(fp_line
			(start -2.7178 -0.508)
			(end -2.1844 -0.0508)
			(stroke
				(width 0.1524)
				(type default)
			)
			(layer "F.SilkS")
		)
		(fp_line
			(start -2.6289 3.4417)
			(end -2.6289 1.4732)
			(stroke
				(width 0.381)
				(type default)
			)
			(layer "F.SilkS")
		)
		(fp_line
			(start -2.1844 -0.0508)
			(end -2.7178 0.508)
			(stroke
				(width 0.1524)
				(type default)
			)
			(layer "F.SilkS")
		)
		(fp_line
			(start 2.1336 -1.4224)
			(end -2.7432 -1.4224)
			(stroke
				(width 0.1524)
				(type default)
			)
			(layer "F.SilkS")
		)
		(fp_line
			(start 2.1336 1.4224)
			(end 2.1336 -1.4224)
			(stroke
				(width 0.1524)
				(type default)
			)
			(layer "F.SilkS")
		)
		(fp_poly
			(pts
				(xy -2.2098 -1.4224) (xy -2.2098 1.4224) (xy 2.2098 1.4224) (xy 2.2098 -1.4224)
			)
			(stroke
				(width 0)
				(type default)
			)
			(fill yes)
			(layer "F.SilkS")
		)
		(fp_rect
			(start -2.450084 2.999994)
			(end 2.450084 -2.999994)
			(stroke
				(width 0)
				(type default)
			)
			(fill no)
			(layer "F.CrtYd")
		)
		(fp_poly
			(pts
				(xy -2.8194 3.6322) (xy -2.8194 -3.6322) (xy 2.8194 -3.6322) (xy 2.8194 1.18364) (xy 2.450084 1.18364)
				(xy 2.450084 -2.999994) (xy -2.450084 -2.999994) (xy -2.450084 2.999994) (xy 2.450084 2.999994)
				(xy 2.450084 1.18618) (xy 2.8194 1.18618) (xy 2.8194 3.6322)
			)
			(stroke
				(width 0)
				(type default)
			)
			(fill no)
			(layer "F.CrtYd")
		)
		(fp_rect
			(start -2.8194 3.6322)
			(end 2.8194 -3.6322)
			(stroke
				(width 0)
				(type default)
			)
			(fill no)
			(layer "F.Fab")
		)
		(pad "1" smd rect
			(at -1.905 2.54)
			(size 0.635 1.651)
			(layers "F.Cu" "F.Mask" "F.Paste")
			(net "P12V_A")
		)
		(pad "2" smd rect
			(at -0.635 2.54)
			(size 0.635 1.651)
			(layers "F.Cu" "F.Mask" "F.Paste")
			(net "P12V_A")
		)
		(pad "3" smd rect
			(at 0.635 2.54)
			(size 0.635 1.651)
			(layers "F.Cu" "F.Mask" "F.Paste")
			(net "P12V_A")
		)
		(pad "4" smd rect
			(at 1.905 2.54)
			(size 0.635 1.651)
			(layers "F.Cu" "F.Mask" "F.Paste")
			(net "SW_HDD_N33")
		)
		(pad "5" smd rect
			(at 1.905 -2.54)
			(size 0.635 1.651)
			(layers "F.Cu" "F.Mask" "F.Paste")
			(net "P12V_HDD33")
		)
		(pad "6" smd rect
			(at 0.635 -2.54)
			(size 0.635 1.651)
			(layers "F.Cu" "F.Mask" "F.Paste")
			(net "P12V_HDD33")
		)
		(pad "7" smd rect
			(at -0.635 -2.54)
			(size 0.635 1.651)
			(layers "F.Cu" "F.Mask" "F.Paste")
			(net "P12V_HDD33")
		)
		(pad "8" smd rect
			(at -1.905 -2.54)
			(size 0.635 1.651)
			(layers "F.Cu" "F.Mask" "F.Paste")
			(net "P12V_HDD33")
		)
	)
	(footprint ""
		(layer "F.Cu")
		(at 318.262 -176.127918 -90)
		(property "Reference" "C279"
			(at 0 0 270)
			(layer "F.SilkS")
			(hide yes)
			(effects
				(font
					(size 1.27 1.27)
				)
			)
		)
		(property "Value" "SCD01U50V2KX-1GP"
			(at 1.1811 -2.7051 270)
			(unlocked yes)
			(layer "F.Fab")
			(hide yes)
			(effects
				(font
					(size 1.016 1.016)
					(thickness 0.1524)
				)
			)
		)
		(property "Device Type" "C402H22"
			(at 1.1811 -4.2291 270)
			(unlocked yes)
			(layer "F.Fab")
			(hide yes)
			(effects
				(font
					(size 1.016 1.016)
					(thickness 0.1524)
				)
			)
		)
		(duplicate_pad_numbers_are_jumpers no)
		(fp_rect
			(start -0.4318 0.9525)
			(end 0.4318 -0.9525)
			(stroke
				(width 0)
				(type default)
			)
			(fill no)
			(layer "F.CrtYd")
		)
		(fp_rect
			(start -0.4318 0.9525)
			(end 0.4318 -0.9525)
			(stroke
				(width 0)
				(type default)
			)
			(fill no)
			(layer "F.Fab")
		)
		(pad "1" smd custom
			(at 0 -0.4445 270)
			(size 0.1524 0.1524)
			(layers "F.Cu" "F.Mask" "F.Paste")
			(net "HDD_PRSNT_18")
			(options
				(clearance outline)
				(anchor circle)
			)
			(primitives
				(gr_poly
					(pts
						(arc
							(start 0.3048 -0.2032)
							(mid 0.275042 -0.275042)
							(end 0.2032 -0.3048)
						)
						(arc
							(start -0.2032 -0.3048)
							(mid -0.275042 -0.275042)
							(end -0.3048 -0.2032)
						)
						(arc
							(start -0.3048 0.2032)
							(mid -0.275042 0.275042)
							(end -0.2032 0.3048)
						)
						(arc
							(start 0.2032 0.3048)
							(mid 0.275042 0.275042)
							(end 0.3048 0.2032)
						)
					)
					(width 0)
					(fill yes)
				)
			)
		)
		(pad "2" smd custom
			(at 0 0.4445 270)
			(size 0.1524 0.1524)
			(layers "F.Cu" "F.Mask" "F.Paste")
			(net "GND")
			(options
				(clearance outline)
				(anchor circle)
			)
			(primitives
				(gr_poly
					(pts
						(arc
							(start 0.3048 -0.2032)
							(mid 0.275042 -0.275042)
							(end 0.2032 -0.3048)
						)
						(arc
							(start -0.2032 -0.3048)
							(mid -0.275042 -0.275042)
							(end -0.3048 -0.2032)
						)
						(arc
							(start -0.3048 0.2032)
							(mid -0.275042 0.275042)
							(end -0.2032 0.3048)
						)
						(arc
							(start 0.2032 0.3048)
							(mid 0.275042 0.275042)
							(end 0.3048 0.2032)
						)
					)
					(width 0)
					(fill yes)
				)
			)
		)
	)
	(footprint ""
		(layer "F.Cu")
		(at 83.530948 -48.554894 180)
		(property "Reference" "Q157"
			(at 0 0 180)
			(layer "F.SilkS")
			(hide yes)
			(effects
				(font
					(size 1.27 1.27)
				)
			)
		)
		(property "Value" "2N7002KDW-GP"
			(at -2.3622 -8.2042 180)
			(unlocked yes)
			(layer "F.Fab")
			(hide yes)
			(effects
				(font
					(size 1.016 1.016)
					(thickness 0.1524)
				)
			)
		)
		(property "Device Type" "SOT-363H44"
			(at -2.3622 -10.1092 180)
			(unlocked yes)
			(layer "F.Fab")
			(hide yes)
			(effects
				(font
					(size 1.016 1.016)
					(thickness 0.1524)
				)
			)
		)
		(duplicate_pad_numbers_are_jumpers no)
		(fp_line
			(start 1.4478 1.7018)
			(end 1.4478 -1.7018)
			(stroke
				(width 0.1524)
				(type default)
			)
			(layer "F.SilkS")
		)
		(fp_line
			(start 1.4478 -1.7018)
			(end -1.4478 -1.7018)
			(stroke
				(width 0.1524)
				(type default)
			)
			(layer "F.SilkS")
		)
		(fp_line
			(start -1.27 1.524)
			(end -1.27 0.6604)
			(stroke
				(width 0.4826)
				(type default)
			)
			(layer "F.SilkS")
		)
		(fp_line
			(start -1.4478 1.7018)
			(end 1.4478 1.7018)
			(stroke
				(width 0.1524)
				(type default)
			)
			(layer "F.SilkS")
		)
		(fp_line
			(start -1.4478 -1.7018)
			(end -1.4478 1.7018)
			(stroke
				(width 0.1524)
				(type default)
			)
			(layer "F.SilkS")
		)
		(fp_poly
			(pts
				(xy -1.524 -1.778) (xy 1.524 -1.778) (xy 1.524 1.778) (xy -1.524 1.778)
			)
			(stroke
				(width 0)
				(type default)
			)
			(fill no)
			(layer "F.CrtYd")
		)
		(fp_poly
			(pts
				(xy -1.524 -1.778) (xy 1.524 -1.778) (xy 1.524 1.778) (xy -1.524 1.778)
			)
			(stroke
				(width 0)
				(type default)
			)
			(fill no)
			(layer "F.Fab")
		)
		(pad "1" smd rect
			(at -0.65024 0.9398 180)
			(size 0.4064 1.016)
			(layers "F.Cu" "F.Mask" "F.Paste")
			(net "GND")
		)
		(pad "2" smd rect
			(at 0 0.9398 180)
			(size 0.4064 1.016)
			(layers "F.Cu" "F.Mask" "F.Paste")
			(net "SW_PWR_R_HDD26")
		)
		(pad "3" smd rect
			(at 0.65024 0.9398 180)
			(size 0.4064 1.016)
			(layers "F.Cu" "F.Mask" "F.Paste")
			(net "SW_HDD_P26")
		)
		(pad "4" smd rect
			(at 0.65024 -0.9398 180)
			(size 0.4064 1.016)
			(layers "F.Cu" "F.Mask" "F.Paste")
			(net "GND")
		)
		(pad "5" smd rect
			(at 0 -0.9398 180)
			(size 0.4064 1.016)
			(layers "F.Cu" "F.Mask" "F.Paste")
			(net "SW_HDD_G26")
		)
		(pad "6" smd rect
			(at -0.65024 -0.9398 180)
			(size 0.4064 1.016)
			(layers "F.Cu" "F.Mask" "F.Paste")
			(net "SW_HDD_R26")
		)
	)
	(footprint ""
		(layer "F.Cu")
		(at 95.563436 -43.660568 90)
		(property "Reference" "C377"
			(at 0 0 90)
			(layer "F.SilkS")
			(hide yes)
			(effects
				(font
					(size 1.27 1.27)
				)
			)
		)
		(property "Value" "SCD01U16V1KX-GP"
			(at -2.8321 -1.7399 90)
			(unlocked yes)
			(layer "F.Fab")
			(hide yes)
			(effects
				(font
					(size 1.016 1.016)
					(thickness 0.1524)
				)
			)
		)
		(property "Device Type" "C0201H13"
			(at -2.8321 -3.2639 90)
			(unlocked yes)
			(layer "F.Fab")
			(hide yes)
			(effects
				(font
					(size 1.016 1.016)
					(thickness 0.1524)
				)
			)
		)
		(duplicate_pad_numbers_are_jumpers no)
		(fp_rect
			(start -0.2794 0.6477)
			(end 0.2794 -0.6477)
			(stroke
				(width 0)
				(type default)
			)
			(fill no)
			(layer "F.CrtYd")
		)
		(fp_rect
			(start -0.2794 0.6477)
			(end 0.2794 -0.6477)
			(stroke
				(width 0)
				(type default)
			)
			(fill no)
			(layer "F.Fab")
		)
		(pad "1" smd custom
			(at 0 -0.2794 90)
			(size 0.0762 0.0762)
			(layers "F.Cu" "F.Mask" "F.Paste")
			(net "SAS_HDD_RX_P26")
			(options
				(clearance outline)
				(anchor circle)
			)
			(primitives
				(gr_poly
					(pts
						(arc
							(start 0.1524 -0.127)
							(mid 0.137521 -0.162921)
							(end 0.1016 -0.1778)
						)
						(arc
							(start -0.1016 -0.1778)
							(mid -0.137521 -0.162921)
							(end -0.1524 -0.127)
						)
						(arc
							(start -0.1524 0.127)
							(mid -0.137521 0.162921)
							(end -0.1016 0.1778)
						)
						(arc
							(start 0.1016 0.1778)
							(mid 0.137521 0.162921)
							(end 0.1524 0.127)
						)
					)
					(width 0)
					(fill yes)
				)
			)
		)
		(pad "2" smd custom
			(at 0 0.2794 90)
			(size 0.0762 0.0762)
			(layers "F.Cu" "F.Mask" "F.Paste")
			(net "PHY_SCC_A_TO_DRV_A_26_DP")
			(options
				(clearance outline)
				(anchor circle)
			)
			(primitives
				(gr_poly
					(pts
						(arc
							(start 0.1524 -0.127)
							(mid 0.137521 -0.162921)
							(end 0.1016 -0.1778)
						)
						(arc
							(start -0.1016 -0.1778)
							(mid -0.137521 -0.162921)
							(end -0.1524 -0.127)
						)
						(arc
							(start -0.1524 0.127)
							(mid -0.137521 0.162921)
							(end -0.1016 0.1778)
						)
						(arc
							(start 0.1016 0.1778)
							(mid 0.137521 0.162921)
							(end 0.1524 0.127)
						)
					)
					(width 0)
					(fill yes)
				)
			)
		)
	)
	(footprint ""
		(layer "F.Cu")
		(at 471.955114 -279.091898 90)
		(property "Reference" "R390"
			(at 0 0 90)
			(layer "F.SilkS")
			(hide yes)
			(effects
				(font
					(size 1.27 1.27)
				)
			)
		)
		(property "Value" "4K7R2J-2-GP"
			(at 0.064008 -3.993896 90)
			(unlocked yes)
			(layer "F.Fab")
			(hide yes)
			(effects
				(font
					(size 1.016 1.016)
					(thickness 0.1524)
				)
			)
		)
		(property "Device Type" "R402H16"
			(at 0.064008 -5.517896 90)
			(unlocked yes)
			(layer "F.Fab")
			(hide yes)
			(effects
				(font
					(size 1.016 1.016)
					(thickness 0.1524)
				)
			)
		)
		(duplicate_pad_numbers_are_jumpers no)
		(fp_line
			(start 0.508 -0.9398)
			(end -0.508 -0.9398)
			(stroke
				(width 0.1524)
				(type default)
			)
			(layer "F.SilkS")
		)
		(fp_line
			(start -0.508 -0.9398)
			(end -0.508 0.9398)
			(stroke
				(width 0.1524)
				(type default)
			)
			(layer "F.SilkS")
		)
		(fp_rect
			(start -0.508 0.9398)
			(end 0.508 -0.9398)
			(stroke
				(width 0)
				(type default)
			)
			(fill no)
			(layer "F.CrtYd")
		)
		(fp_rect
			(start -0.508 0.9398)
			(end 0.508 -0.9398)
			(stroke
				(width 0)
				(type default)
			)
			(fill no)
			(layer "F.Fab")
		)
		(pad "1" smd custom
			(at 0 -0.4445 90)
			(size 0.1397 0.1397)
			(layers "F.Cu" "F.Mask" "F.Paste")
			(net "P12V_A")
			(options
				(clearance outline)
				(anchor circle)
			)
			(primitives
				(gr_poly
					(pts
						(arc
							(start -0.1778 -0.2794)
							(mid -0.249642 -0.249642)
							(end -0.2794 -0.1778)
						)
						(arc
							(start -0.2794 0.1778)
							(mid -0.249642 0.249642)
							(end -0.1778 0.2794)
						)
						(arc
							(start 0.1778 0.2794)
							(mid 0.249642 0.249642)
							(end 0.2794 0.1778)
						)
						(arc
							(start 0.2794 -0.1778)
							(mid 0.249642 -0.249642)
							(end 0.1778 -0.2794)
						)
					)
					(width 0)
					(fill yes)
				)
			)
		)
		(pad "2" smd custom
			(at 0 0.4445 90)
			(size 0.1397 0.1397)
			(layers "F.Cu" "F.Mask" "F.Paste")
			(net "SW_HDD_P11")
			(options
				(clearance outline)
				(anchor circle)
			)
			(primitives
				(gr_poly
					(pts
						(arc
							(start -0.1778 -0.2794)
							(mid -0.249642 -0.249642)
							(end -0.2794 -0.1778)
						)
						(arc
							(start -0.2794 0.1778)
							(mid -0.249642 0.249642)
							(end -0.1778 0.2794)
						)
						(arc
							(start 0.1778 0.2794)
							(mid 0.249642 0.249642)
							(end 0.2794 0.1778)
						)
						(arc
							(start 0.2794 -0.1778)
							(mid 0.249642 -0.249642)
							(end 0.1778 -0.2794)
						)
					)
					(width 0)
					(fill yes)
				)
			)
		)
	)
	(footprint ""
		(layer "F.Cu")
		(at 458.9399 -278.554942 -90)
		(property "Reference" "R367"
			(at 0 0 270)
			(layer "F.SilkS")
			(hide yes)
			(effects
				(font
					(size 1.27 1.27)
				)
			)
		)
		(property "Value" "4K7R2J-2-GP"
			(at 0.064008 -3.993896 270)
			(unlocked yes)
			(layer "F.Fab")
			(hide yes)
			(effects
				(font
					(size 1.016 1.016)
					(thickness 0.1524)
				)
			)
		)
		(property "Device Type" "R402H16"
			(at 0.064008 -5.517896 270)
			(unlocked yes)
			(layer "F.Fab")
			(hide yes)
			(effects
				(font
					(size 1.016 1.016)
					(thickness 0.1524)
				)
			)
		)
		(duplicate_pad_numbers_are_jumpers no)
		(fp_line
			(start -0.508 -0.9398)
			(end -0.508 0.9398)
			(stroke
				(width 0.1524)
				(type default)
			)
			(layer "F.SilkS")
		)
		(fp_line
			(start 0.508 -0.9398)
			(end -0.508 -0.9398)
			(stroke
				(width 0.1524)
				(type default)
			)
			(layer "F.SilkS")
		)
		(fp_rect
			(start -0.508 0.9398)
			(end 0.508 -0.9398)
			(stroke
				(width 0)
				(type default)
			)
			(fill no)
			(layer "F.CrtYd")
		)
		(fp_rect
			(start -0.508 0.9398)
			(end 0.508 -0.9398)
			(stroke
				(width 0)
				(type default)
			)
			(fill no)
			(layer "F.Fab")
		)
		(pad "1" smd custom
			(at 0 -0.4445 270)
			(size 0.1397 0.1397)
			(layers "F.Cu" "F.Mask" "F.Paste")
			(net "P12V_A")
			(options
				(clearance outline)
				(anchor circle)
			)
			(primitives
				(gr_poly
					(pts
						(arc
							(start -0.1778 -0.2794)
							(mid -0.249642 -0.249642)
							(end -0.2794 -0.1778)
						)
						(arc
							(start -0.2794 0.1778)
							(mid -0.249642 0.249642)
							(end -0.1778 0.2794)
						)
						(arc
							(start 0.1778 0.2794)
							(mid 0.249642 0.249642)
							(end 0.2794 0.1778)
						)
						(arc
							(start 0.2794 -0.1778)
							(mid 0.249642 -0.249642)
							(end 0.1778 -0.2794)
						)
					)
					(width 0)
					(fill yes)
				)
			)
		)
		(pad "2" smd custom
			(at 0 0.4445 270)
			(size 0.1397 0.1397)
			(layers "F.Cu" "F.Mask" "F.Paste")
			(net "SW_HDD_P10")
			(options
				(clearance outline)
				(anchor circle)
			)
			(primitives
				(gr_poly
					(pts
						(arc
							(start -0.1778 -0.2794)
							(mid -0.249642 -0.249642)
							(end -0.2794 -0.1778)
						)
						(arc
							(start -0.2794 0.1778)
							(mid -0.249642 0.249642)
							(end -0.1778 0.2794)
						)
						(arc
							(start 0.1778 0.2794)
							(mid 0.249642 0.249642)
							(end 0.2794 0.1778)
						)
						(arc
							(start 0.2794 -0.1778)
							(mid 0.249642 -0.249642)
							(end 0.1778 -0.2794)
						)
					)
					(width 0)
					(fill yes)
				)
			)
		)
	)
	(footprint ""
		(layer "F.Cu")
		(at 396.672054 -184.450228 -90)
		(property "Reference" "R591"
			(at 0 0 270)
			(layer "F.SilkS")
			(hide yes)
			(effects
				(font
					(size 1.27 1.27)
				)
			)
		)
		(property "Value" "2R6F-GP"
			(at -0.0508 -4.8514 270)
			(unlocked yes)
			(layer "F.Fab")
			(hide yes)
			(effects
				(font
					(size 1.016 1.016)
					(thickness 0.1524)
				)
			)
		)
		(property "Device Type" "R1206H26"
			(at 0 -6.3754 270)
			(unlocked yes)
			(layer "F.Fab")
			(hide yes)
			(effects
				(font
					(size 1.016 1.016)
					(thickness 0.1524)
				)
			)
		)
		(duplicate_pad_numbers_are_jumpers no)
		(fp_line
			(start -1.016 2.2352)
			(end -1.016 -2.2352)
			(stroke
				(width 0.1524)
				(type default)
			)
			(layer "F.SilkS")
		)
		(fp_line
			(start 1.016 2.2352)
			(end -1.016 2.2352)
			(stroke
				(width 0.1524)
				(type default)
			)
			(layer "F.SilkS")
		)
		(fp_line
			(start -1.016 -2.2352)
			(end 1.016 -2.2352)
			(stroke
				(width 0.1524)
				(type default)
			)
			(layer "F.SilkS")
		)
		(fp_line
			(start 1.016 -2.2352)
			(end 1.016 2.2352)
			(stroke
				(width 0.1524)
				(type default)
			)
			(layer "F.SilkS")
		)
		(fp_rect
			(start -1.0922 2.3114)
			(end 1.0922 -2.3114)
			(stroke
				(width 0)
				(type default)
			)
			(fill no)
			(layer "F.CrtYd")
		)
		(fp_poly
			(pts
				(xy -1.0922 -2.3114) (xy 1.0922 -2.3114) (xy 1.0922 2.3114) (xy -1.0922 2.3114)
			)
			(stroke
				(width 0)
				(type default)
			)
			(fill no)
			(layer "F.Fab")
		)
		(pad "1" smd rect
			(at 0 -1.397 270)
			(size 1.651 1.27)
			(layers "F.Cu" "F.Mask" "F.Paste")
			(net "P12V_HDD20")
		)
		(pad "2" smd rect
			(at 0 1.397 270)
			(size 1.651 1.27)
			(layers "F.Cu" "F.Mask" "F.Paste")
			(net "12V_PRE_20")
		)
	)
)
